# T6G (Grand Teton) — schematic netlist excerpt (pin names and nets, part order shuffled) for the footprints in the layout excerpt that follows; sources: Cadence DE-HDL packaged netlist, KiCad conversion of 04192023_DAF0TMB3IC0_F0TG_MB_C_brd_V02_OCP.brd

PR500  Q_RES  1.5 1% EMPTY  pkg 0402LF  page 196 : A = SW_PVDDCR_CPU0_P0_SW6_RC ; B = GND
R3623  Q_RES  4.7K 1% CHIP  pkg 0402LF  page 237 : A = P3V3_AUX ; B = INA230_4_A1
C919  Q_CAP_DIFFBUS  DIFF BUS_0.22UF 6.3V 20% X6S  pkg C0201  page 63 : \1\ = P5E_CPU0_P0_TX_C_DP<7> ; \2\ = P5E_CPU0_P0_TX_DP<7>

(kicad_pcb
	(version 20260206)
	(generator "pcbnew")
	(generator_version "10.0")
	(general
		(thickness 1.6)
		(legacy_teardrops no)
	)
	(paper "A4")
	(title_block
		(title "04192023_DAF0TMB3IC0_F0TG_MB_C_brd_V02_OCP.brd")
		(comment 1 "Grand Teton / footprints 2090-2092 of 8354")
	)
	(layers
		(0 "F.Cu" signal "TOP")
		(4 "In1.Cu" signal "GND")
		(6 "In2.Cu" signal "IN1")
		(8 "In3.Cu" signal "GND1")
		(10 "In4.Cu" signal "IN2")
		(12 "In5.Cu" signal "GND2")
		(14 "In6.Cu" signal "IN3")
		(16 "In7.Cu" signal "GND3")
		(18 "In8.Cu" signal "VCC")
		(20 "In9.Cu" signal "VCC1")
		(22 "In10.Cu" signal "GND4")
		(24 "In11.Cu" signal "IN4")
		(26 "In12.Cu" signal "GND5")
		(28 "In13.Cu" signal "IN5")
		(30 "In14.Cu" signal "GND6")
		(32 "In15.Cu" signal "IN6")
		(34 "In16.Cu" signal "GND7")
		(2 "B.Cu" signal "BOTTOM")
		(9 "F.Adhes" user "F.Adhesive")
		(11 "B.Adhes" user "B.Adhesive")
		(13 "F.Paste" user "Package Geometry/Pastemask Top")
		(15 "B.Paste" user "Package Geometry/Pastemask Bottom")
		(5 "F.SilkS" user "Ref Des/Silkscreen Top")
		(7 "B.SilkS" user "Ref Des/Silkscreen Bottom")
		(1 "F.Mask" user "Board Geometry/Soldermask Top")
		(3 "B.Mask" user "Board Geometry/Soldermask Bottom")
		(17 "Dwgs.User" user "User.Drawings")
		(19 "Cmts.User" user "User.Comments")
		(21 "Eco1.User" user "User.Eco1")
		(23 "Eco2.User" user "User.Eco2")
		(25 "Edge.Cuts" user "Board Geometry/Outline")
		(27 "Margin" user)
		(31 "F.CrtYd" user "Package Geometry/Place Bound Top")
		(29 "B.CrtYd" user "Package Geometry/Place Bound Bottom")
		(35 "F.Fab" user "Ref Des/Assembly Top")
		(33 "B.Fab" user "Ref Des/Assembly Bottom")
	)
	(footprint ""
		(layer "F.Cu")
		(at 150.502366 -57.220358)
		(property "Reference" "R3623"
			(at 0 0 0)
			(layer "F.SilkS")
			(hide yes)
			(effects
				(font
					(size 1.27 1.27)
				)
			)
		)
		(property "Value" ""
			(at 0 0 0)
			(layer "F.Fab")
			(effects
				(font
					(size 1.27 1.27)
				)
			)
		)
		(duplicate_pad_numbers_are_jumpers no)
		(fp_line
			(start -0.7874 -0.4064)
			(end 0.7874 -0.4064)
			(stroke
				(width 0.1524)
				(type default)
			)
			(layer "F.SilkS")
		)
		(fp_line
			(start -0.7874 0.4064)
			(end -0.7874 -0.4064)
			(stroke
				(width 0.1524)
				(type default)
			)
			(layer "F.SilkS")
		)
		(fp_line
			(start 0.7874 -0.4064)
			(end 0.7874 0.4064)
			(stroke
				(width 0.1524)
				(type default)
			)
			(layer "F.SilkS")
		)
		(fp_line
			(start 0.7874 0.4064)
			(end -0.7874 0.4064)
			(stroke
				(width 0.1524)
				(type default)
			)
			(layer "F.SilkS")
		)
		(fp_line
			(start -0.67945 -0.305054)
			(end -0.12065 -0.305054)
			(stroke
				(width 0.1)
				(type default)
			)
			(layer "F.Fab")
		)
		(fp_line
			(start -0.67945 0.3048)
			(end -0.67945 -0.305054)
			(stroke
				(width 0.1)
				(type default)
			)
			(layer "F.Fab")
		)
		(fp_line
			(start -0.12065 -0.305054)
			(end -0.12065 -0.2794)
			(stroke
				(width 0.1)
				(type default)
			)
			(layer "F.Fab")
		)
		(fp_line
			(start -0.12065 -0.2794)
			(end 0.12065 -0.2794)
			(stroke
				(width 0.1)
				(type default)
			)
			(layer "F.Fab")
		)
		(fp_line
			(start -0.12065 0.2794)
			(end -0.12065 0.3048)
			(stroke
				(width 0.1)
				(type default)
			)
			(layer "F.Fab")
		)
		(fp_line
			(start -0.12065 0.3048)
			(end -0.67945 0.3048)
			(stroke
				(width 0.1)
				(type default)
			)
			(layer "F.Fab")
		)
		(fp_line
			(start 0.120396 0.2794)
			(end -0.12065 0.2794)
			(stroke
				(width 0.1)
				(type default)
			)
			(layer "F.Fab")
		)
		(fp_line
			(start 0.120396 0.3048)
			(end 0.120396 0.2794)
			(stroke
				(width 0.1)
				(type default)
			)
			(layer "F.Fab")
		)
		(fp_line
			(start 0.12065 -0.3048)
			(end 0.67945 -0.3048)
			(stroke
				(width 0.1)
				(type default)
			)
			(layer "F.Fab")
		)
		(fp_line
			(start 0.12065 -0.2794)
			(end 0.12065 -0.3048)
			(stroke
				(width 0.1)
				(type default)
			)
			(layer "F.Fab")
		)
		(fp_line
			(start 0.67945 -0.3048)
			(end 0.67945 0.3048)
			(stroke
				(width 0.1)
				(type default)
			)
			(layer "F.Fab")
		)
		(fp_line
			(start 0.67945 0.3048)
			(end 0.120396 0.3048)
			(stroke
				(width 0.1)
				(type default)
			)
			(layer "F.Fab")
		)
		(pad "1" smd circle
			(at -0.40005 0)
			(size 0 0)
			(layers "F.Cu" "F.Mask" "F.Paste")
			(net "P3V3_AUX")
		)
		(pad "2" smd circle
			(at 0.40005 0)
			(size 0 0)
			(layers "F.Cu" "F.Mask" "F.Paste")
			(net "INA230_4_A1")
		)
	)
	(footprint ""
		(layer "F.Cu")
		(at 351.404936 -162.87369 -90)
		(property "Reference" "PR500"
			(at 0 0 270)
			(layer "F.SilkS")
			(hide yes)
			(effects
				(font
					(size 1.27 1.27)
				)
			)
		)
		(property "Value" ""
			(at 0 0 270)
			(layer "F.Fab")
			(effects
				(font
					(size 1.27 1.27)
				)
			)
		)
		(duplicate_pad_numbers_are_jumpers no)
		(fp_line
			(start -0.7874 0.4064)
			(end -0.7874 -0.4064)
			(stroke
				(width 0.1524)
				(type default)
			)
			(layer "F.SilkS")
		)
		(fp_line
			(start 0.7874 0.4064)
			(end -0.7874 0.4064)
			(stroke
				(width 0.1524)
				(type default)
			)
			(layer "F.SilkS")
		)
		(fp_line
			(start -0.7874 -0.4064)
			(end 0.7874 -0.4064)
			(stroke
				(width 0.1524)
				(type default)
			)
			(layer "F.SilkS")
		)
		(fp_line
			(start 0.7874 -0.4064)
			(end 0.7874 0.4064)
			(stroke
				(width 0.1524)
				(type default)
			)
			(layer "F.SilkS")
		)
		(fp_line
			(start -0.67945 0.3048)
			(end -0.67945 -0.305054)
			(stroke
				(width 0.1)
				(type default)
			)
			(layer "F.Fab")
		)
		(fp_line
			(start -0.12065 0.3048)
			(end -0.67945 0.3048)
			(stroke
				(width 0.1)
				(type default)
			)
			(layer "F.Fab")
		)
		(fp_line
			(start 0.120396 0.3048)
			(end 0.120396 0.2794)
			(stroke
				(width 0.1)
				(type default)
			)
			(layer "F.Fab")
		)
		(fp_line
			(start 0.67945 0.3048)
			(end 0.120396 0.3048)
			(stroke
				(width 0.1)
				(type default)
			)
			(layer "F.Fab")
		)
		(fp_line
			(start -0.12065 0.2794)
			(end -0.12065 0.3048)
			(stroke
				(width 0.1)
				(type default)
			)
			(layer "F.Fab")
		)
		(fp_line
			(start 0.120396 0.2794)
			(end -0.12065 0.2794)
			(stroke
				(width 0.1)
				(type default)
			)
			(layer "F.Fab")
		)
		(fp_line
			(start -0.12065 -0.2794)
			(end 0.12065 -0.2794)
			(stroke
				(width 0.1)
				(type default)
			)
			(layer "F.Fab")
		)
		(fp_line
			(start 0.12065 -0.2794)
			(end 0.12065 -0.3048)
			(stroke
				(width 0.1)
				(type default)
			)
			(layer "F.Fab")
		)
		(fp_line
			(start 0.12065 -0.3048)
			(end 0.67945 -0.3048)
			(stroke
				(width 0.1)
				(type default)
			)
			(layer "F.Fab")
		)
		(fp_line
			(start 0.67945 -0.3048)
			(end 0.67945 0.3048)
			(stroke
				(width 0.1)
				(type default)
			)
			(layer "F.Fab")
		)
		(fp_line
			(start -0.67945 -0.305054)
			(end -0.12065 -0.305054)
			(stroke
				(width 0.1)
				(type default)
			)
			(layer "F.Fab")
		)
		(fp_line
			(start -0.12065 -0.305054)
			(end -0.12065 -0.2794)
			(stroke
				(width 0.1)
				(type default)
			)
			(layer "F.Fab")
		)
		(pad "1" smd circle
			(at -0.40005 0 270)
			(size 0 0)
			(layers "F.Cu" "F.Mask" "F.Paste")
			(net "SW_PVDDCR_CPU0_P0_SW6_RC")
		)
		(pad "2" smd circle
			(at 0.40005 0 270)
			(size 0 0)
			(layers "F.Cu" "F.Mask" "F.Paste")
			(net "GND")
		)
	)
	(footprint ""
		(layer "F.Cu")
		(at 310.902096 -383.88163 -90)
		(property "Reference" "C919"
			(at 0 0 270)
			(layer "F.SilkS")
			(hide yes)
			(effects
				(font
					(size 1.27 1.27)
				)
			)
		)
		(property "Value" ""
			(at 0 0 270)
			(layer "F.Fab")
			(effects
				(font
					(size 1.27 1.27)
				)
			)
		)
		(duplicate_pad_numbers_are_jumpers no)
		(fp_line
			(start -0.299974 0.150114)
			(end -0.299974 -0.150114)
			(stroke
				(width 0.1)
				(type default)
			)
			(layer "F.Fab")
		)
		(fp_line
			(start 0.299974 0.150114)
			(end -0.299974 0.150114)
			(stroke
				(width 0.1)
				(type default)
			)
			(layer "F.Fab")
		)
		(fp_line
			(start -0.299974 -0.150114)
			(end 0.299974 -0.150114)
			(stroke
				(width 0.1)
				(type default)
			)
			(layer "F.Fab")
		)
		(fp_line
			(start 0.299974 -0.150114)
			(end 0.299974 0.150114)
			(stroke
				(width 0.1)
				(type default)
			)
			(layer "F.Fab")
		)
		(pad "1" smd rect
			(at -0.2667 0 270)
			(size 0.3048 0.381)
			(layers "F.Cu" "F.Mask" "F.Paste")
			(net "P5E_CPU0_P0_TX_C_DP<7>")
		)
		(pad "2" smd rect
			(at 0.2667 0 270)
			(size 0.3048 0.381)
			(layers "F.Cu" "F.Mask" "F.Paste")
			(net "P5E_CPU0_P0_TX_DP<7>")
		)
	)
)
